(kicad_pcb
	(version 20211014)
	(generator pcbnew)
	(general
    (thickness 1.6)
  )
	(paper "A4")
	(title_block
    (title "SA800U (Snapdragon 845) Baseboard")
    (date "2023-10-19")
    (rev "1.0.3")
    (company "Antmicro Ltd.")
    (comment 1 "www.antmicro.com")
		(comment 9 "footprints 110-119 of 589")
	)
	(layers
    (0 "F.Cu" signal)
    (1 "In1.Cu" power)
    (2 "In2.Cu" signal)
    (3 "In3.Cu" signal)
    (4 "In4.Cu" power)
    (31 "B.Cu" signal)
    (32 "B.Adhes" user "B.Adhesive")
    (33 "F.Adhes" user "F.Adhesive")
    (34 "B.Paste" user)
    (35 "F.Paste" user)
    (36 "B.SilkS" user "B.Silkscreen")
    (37 "F.SilkS" user "F.Silkscreen")
    (38 "B.Mask" user)
    (39 "F.Mask" user)
    (40 "Dwgs.User" user "User.Drawings")
    (41 "Cmts.User" user "User.Comments")
    (42 "Eco1.User" user "User.Eco1")
    (43 "Eco2.User" user "User.Eco2")
    (44 "Edge.Cuts" user)
    (45 "Margin" user)
    (46 "B.CrtYd" user "B.Courtyard")
    (47 "F.CrtYd" user "F.Courtyard")
    (48 "B.Fab" user)
    (49 "F.Fab" user)
  )
	(footprint "sa800u-baseboard-hw-footprints:C_0402_1005Metric" (layer "F.Cu")
    (tedit 616D63CF)
    (at 109.02 93.8 90)
    (descr "Capacitor SMD 0402")
    (tags "capacitor SMD 0402")
    (property "Author" "Antmicro")
    (property "Dielectric" "X5R")
    (property "License" "Apache-2.0")
    (property "MPN" "GRM155R61H104KE14D")
    (property "Manufacturer" "Murata")
    (property "Sheetfile" "camera-interface.kicad_sch")
    (property "Sheetname" "Camera Interface")
    (property "Val" "100n")
    (property "Voltage" "50V")
    (attr smd)
    (fp_text reference "C107" (at -1.75 -0.65 90) (layer "F.SilkS")
      (effects (font (size 0.7 0.7) (thickness 0.15)) (justify left bottom))
    )
    (fp_text value "C_100n_0402" (at 0 1.4 90) (layer "F.Fab")
      (effects (font (size 0.7 0.7) (thickness 0.15)) (justify left bottom))
    )
    (fp_text user "${REFERENCE}" (at -0.932 3.168 90) (layer "F.Fab") hide
      (effects (font (size 0.7 0.7) (thickness 0.15)) (justify left bottom))
    )
    (fp_text user "Author: Antmicro" (at -0.932 4.17 90) (layer "F.Fab") hide
      (effects (font (size 0.7 0.7) (thickness 0.15)) (justify left bottom))
    )
    (fp_text user "License: Apache-2.0" (at -0.932 5.17 90) (layer "F.Fab") hide
      (effects (font (size 0.7 0.7) (thickness 0.15)) (justify left bottom))
    )
    (fp_rect (start -0.94 -0.47) (end 0.94 0.47) (layer "F.CrtYd") (width 0.05) (fill none))
    (fp_rect (start -0.499 -0.249) (end 0.499 0.249) (layer "F.Fab") (width 0.15) (fill none))
    (pad "1" smd roundrect (at -0.484 0 90) (size 0.59 0.64) (layers "F.Cu" "F.Paste" "F.Mask") (roundrect_rratio 0.25)
      (net 139 "LVS1A_1V8") (pintype "passive"))
    (pad "2" smd roundrect (at 0.484 0 90) (size 0.59 0.64) (layers "F.Cu" "F.Paste" "F.Mask") (roundrect_rratio 0.25)
      (net 1 "GND") (pintype "passive"))
  )
	(footprint "sa800u-baseboard-hw-footprints:C_0402_1005Metric" (layer "F.Cu")
    (tedit 616D63CF)
    (at 112.55 93.8 90)
    (descr "Capacitor SMD 0402")
    (tags "capacitor SMD 0402")
    (property "Author" "Antmicro")
    (property "Dielectric" "X5R")
    (property "License" "Apache-2.0")
    (property "MPN" "GRM155R61H104KE14D")
    (property "Manufacturer" "Murata")
    (property "Sheetfile" "camera-interface.kicad_sch")
    (property "Sheetname" "Camera Interface")
    (property "Val" "100n")
    (property "Voltage" "50V")
    (attr smd)
    (fp_text reference "C106" (at -3.69 0.31 90) (layer "F.SilkS")
      (effects (font (size 0.7 0.7) (thickness 0.15)) (justify left bottom))
    )
    (fp_text value "C_100n_0402" (at 0 1.4 90) (layer "F.Fab")
      (effects (font (size 0.7 0.7) (thickness 0.15)) (justify left bottom))
    )
    (fp_text user "License: Apache-2.0" (at -0.932 5.17 90) (layer "F.Fab") hide
      (effects (font (size 0.7 0.7) (thickness 0.15)) (justify left bottom))
    )
    (fp_text user "${REFERENCE}" (at -0.932 3.168 90) (layer "F.Fab") hide
      (effects (font (size 0.7 0.7) (thickness 0.15)) (justify left bottom))
    )
    (fp_text user "Author: Antmicro" (at -0.932 4.17 90) (layer "F.Fab") hide
      (effects (font (size 0.7 0.7) (thickness 0.15)) (justify left bottom))
    )
    (fp_rect (start -0.94 -0.47) (end 0.94 0.47) (layer "F.CrtYd") (width 0.05) (fill none))
    (fp_rect (start -0.499 -0.249) (end 0.499 0.249) (layer "F.Fab") (width 0.15) (fill none))
    (pad "1" smd roundrect (at -0.484 0 90) (size 0.59 0.64) (layers "F.Cu" "F.Paste" "F.Mask") (roundrect_rratio 0.25)
      (net 139 "LVS1A_1V8") (pintype "passive"))
    (pad "2" smd roundrect (at 0.484 0 90) (size 0.59 0.64) (layers "F.Cu" "F.Paste" "F.Mask") (roundrect_rratio 0.25)
      (net 1 "GND") (pintype "passive"))
  )
	(footprint "sa800u-baseboard-hw-footprints:R_0402_1005Metric" (layer "F.Cu")
    (tedit 5FD9C158)
    (at 114.3 91.85 90)
    (descr "Resistor SMD 0402")
    (tags "resistor SMD 0402")
    (property "Author" "Antmicro")
    (property "License" "Apache-2.0")
    (property "MPN" "CR0402-FX-2001GLF")
    (property "Manufacturer" "Bourns")
    (property "Sheetfile" "camera-interface.kicad_sch")
    (property "Sheetname" "Camera Interface")
    (property "Tolerance" "1%")
    (property "Val" "2k")
    (attr smd)
    (fp_text reference "R86" (at -1.01 1.17 90) (layer "F.SilkS")
      (effects (font (size 0.7 0.7) (thickness 0.15)) (justify left bottom))
    )
    (fp_text value "R_2k_0402" (at 0 1.4 90) (layer "F.Fab")
      (effects (font (size 0.7 0.7) (thickness 0.15)) (justify left bottom))
    )
    (fp_text user "${REFERENCE}" (at -0.95 3.168 90) (layer "F.Fab") hide
      (effects (font (size 0.7 0.7) (thickness 0.15)) (justify left bottom))
    )
    (fp_text user "Author: Antmicro" (at -0.95 4.169 90) (layer "F.Fab") hide
      (effects (font (size 0.7 0.7) (thickness 0.15)) (justify left bottom))
    )
    (fp_text user "License: Apache-2.0" (at -0.95 5.169 90) (layer "F.Fab") hide
      (effects (font (size 0.7 0.7) (thickness 0.15)) (justify left bottom))
    )
    (fp_rect (start -0.93 -0.47) (end 0.93 0.47) (layer "F.CrtYd") (width 0.05) (fill none))
    (fp_rect (start -0.5 -0.25) (end 0.5 0.25) (layer "F.Fab") (width 0.15) (fill none))
    (pad "1" smd roundrect (at -0.485 0 90) (size 0.59 0.64) (layers "F.Cu" "F.Paste" "F.Mask") (roundrect_rratio 0.25)
      (net 293 "/Camera Interface/CCI1_I2C_SCL_3V3") (pintype "passive"))
    (pad "2" smd roundrect (at 0.485 0 90) (size 0.59 0.64) (layers "F.Cu" "F.Paste" "F.Mask") (roundrect_rratio 0.25)
      (net 231 "/Camera Interface/3V3_CAM") (pintype "passive"))
  )
	(footprint "sa800u-baseboard-hw-footprints:R_0402_1005Metric" (layer "F.Cu")
    (tedit 5FD9C158)
    (at 113.3 91.85 90)
    (descr "Resistor SMD 0402")
    (tags "resistor SMD 0402")
    (property "Author" "Antmicro")
    (property "License" "Apache-2.0")
    (property "MPN" "CR0402-FX-2001GLF")
    (property "Manufacturer" "Bourns")
    (property "Sheetfile" "camera-interface.kicad_sch")
    (property "Sheetname" "Camera Interface")
    (property "Tolerance" "1%")
    (property "Val" "2k")
    (attr smd)
    (fp_text reference "R88" (at -1.05 -0.57 90) (layer "F.SilkS")
      (effects (font (size 0.7 0.7) (thickness 0.15)) (justify left bottom))
    )
    (fp_text value "R_2k_0402" (at 0 1.4 90) (layer "F.Fab")
      (effects (font (size 0.7 0.7) (thickness 0.15)) (justify left bottom))
    )
    (fp_text user "License: Apache-2.0" (at -0.95 5.169 90) (layer "F.Fab") hide
      (effects (font (size 0.7 0.7) (thickness 0.15)) (justify left bottom))
    )
    (fp_text user "Author: Antmicro" (at -0.95 4.169 90) (layer "F.Fab") hide
      (effects (font (size 0.7 0.7) (thickness 0.15)) (justify left bottom))
    )
    (fp_text user "${REFERENCE}" (at -0.95 3.168 90) (layer "F.Fab") hide
      (effects (font (size 0.7 0.7) (thickness 0.15)) (justify left bottom))
    )
    (fp_rect (start -0.93 -0.47) (end 0.93 0.47) (layer "F.CrtYd") (width 0.05) (fill none))
    (fp_rect (start -0.5 -0.25) (end 0.5 0.25) (layer "F.Fab") (width 0.15) (fill none))
    (pad "1" smd roundrect (at -0.485 0 90) (size 0.59 0.64) (layers "F.Cu" "F.Paste" "F.Mask") (roundrect_rratio 0.25)
      (net 295 "/Camera Interface/CCI1_I2C_SDA_3V3") (pintype "passive"))
    (pad "2" smd roundrect (at 0.485 0 90) (size 0.59 0.64) (layers "F.Cu" "F.Paste" "F.Mask") (roundrect_rratio 0.25)
      (net 231 "/Camera Interface/3V3_CAM") (pintype "passive"))
  )
	(footprint "sa800u-baseboard-hw-footprints:R_0402_1005Metric" (layer "F.Cu")
    (tedit 5FD9C158)
    (at 109.8 91.85 90)
    (descr "Resistor SMD 0402")
    (tags "resistor SMD 0402")
    (property "Author" "Antmicro")
    (property "License" "Apache-2.0")
    (property "MPN" "CR0402-FX-2001GLF")
    (property "Manufacturer" "Bourns")
    (property "Sheetfile" "camera-interface.kicad_sch")
    (property "Sheetname" "Camera Interface")
    (property "Tolerance" "1%")
    (property "Val" "2k")
    (attr smd)
    (fp_text reference "R89" (at -0.94 -1.65 90) (layer "F.SilkS")
      (effects (font (size 0.7 0.7) (thickness 0.15)) (justify left bottom))
    )
    (fp_text value "R_2k_0402" (at 0 1.4 90) (layer "F.Fab")
      (effects (font (size 0.7 0.7) (thickness 0.15)) (justify left bottom))
    )
    (fp_text user "${REFERENCE}" (at -0.95 3.168 90) (layer "F.Fab") hide
      (effects (font (size 0.7 0.7) (thickness 0.15)) (justify left bottom))
    )
    (fp_text user "License: Apache-2.0" (at -0.95 5.169 90) (layer "F.Fab") hide
      (effects (font (size 0.7 0.7) (thickness 0.15)) (justify left bottom))
    )
    (fp_text user "Author: Antmicro" (at -0.95 4.169 90) (layer "F.Fab") hide
      (effects (font (size 0.7 0.7) (thickness 0.15)) (justify left bottom))
    )
    (fp_rect (start -0.93 -0.47) (end 0.93 0.47) (layer "F.CrtYd") (width 0.05) (fill none))
    (fp_rect (start -0.5 -0.25) (end 0.5 0.25) (layer "F.Fab") (width 0.15) (fill none))
    (pad "1" smd roundrect (at -0.485 0 90) (size 0.59 0.64) (layers "F.Cu" "F.Paste" "F.Mask") (roundrect_rratio 0.25)
      (net 296 "/Camera Interface/CCI0_I2C_SDA_3V3") (pintype "passive"))
    (pad "2" smd roundrect (at 0.485 0 90) (size 0.59 0.64) (layers "F.Cu" "F.Paste" "F.Mask") (roundrect_rratio 0.25)
      (net 231 "/Camera Interface/3V3_CAM") (pintype "passive"))
  )
	(footprint "sa800u-baseboard-hw-footprints:R_0402_1005Metric" (layer "F.Cu")
    (tedit 5FD9C158)
    (at 131.1 122.3 -90)
    (descr "Resistor SMD 0402")
    (tags "resistor SMD 0402")
    (property "Author" "Antmicro")
    (property "License" "Apache-2.0")
    (property "MPN" "CR0402-FX-2201GLF")
    (property "Manufacturer" "Bourns")
    (property "Sheetfile" "usb-c-interface.kicad_sch")
    (property "Sheetname" "USB-C Interface ")
    (property "Tolerance" "1%")
    (property "Val" "2k2")
    (attr smd)
    (fp_text reference "R62" (at 1.03 0.56 -90) (layer "F.SilkS")
      (effects (font (size 0.7 0.7) (thickness 0.15)) (justify left bottom))
    )
    (fp_text value "R_2k2_0402" (at 0 1.4 -90) (layer "F.Fab")
      (effects (font (size 0.7 0.7) (thickness 0.15)) (justify left bottom))
    )
    (fp_text user "Author: Antmicro" (at -0.95 4.169 -90) (layer "F.Fab") hide
      (effects (font (size 0.7 0.7) (thickness 0.15)) (justify left bottom))
    )
    (fp_text user "${REFERENCE}" (at -0.95 3.168 -90) (layer "F.Fab") hide
      (effects (font (size 0.7 0.7) (thickness 0.15)) (justify left bottom))
    )
    (fp_text user "License: Apache-2.0" (at -0.95 5.169 -90) (layer "F.Fab") hide
      (effects (font (size 0.7 0.7) (thickness 0.15)) (justify left bottom))
    )
    (fp_rect (start -0.93 -0.47) (end 0.93 0.47) (layer "F.CrtYd") (width 0.05) (fill none))
    (fp_rect (start -0.5 -0.25) (end 0.5 0.25) (layer "F.Fab") (width 0.15) (fill none))
    (pad "1" smd roundrect (at -0.485 0 270) (size 0.59 0.64) (layers "F.Cu" "F.Paste" "F.Mask") (roundrect_rratio 0.25)
      (net 93 "SBU_SW_OE") (pintype "passive"))
    (pad "2" smd roundrect (at 0.485 0 270) (size 0.59 0.64) (layers "F.Cu" "F.Paste" "F.Mask") (roundrect_rratio 0.25)
      (net 132 "VREG_S4A_1V8") (pintype "passive"))
  )
	(footprint "sa800u-baseboard-hw-footprints:R_0402_1005Metric" (layer "F.Cu")
    (tedit 5FD9C158)
    (at 93.1 139.8 90)
    (descr "Resistor SMD 0402")
    (tags "resistor SMD 0402")
    (property "Author" "Antmicro")
    (property "License" "Apache-2.0")
    (property "MPN" "CR0402-FX-1003GLF")
    (property "Manufacturer" "Bourns")
    (property "Sheetfile" "usb-c-interface.kicad_sch")
    (property "Sheetname" "USB-C Interface ")
    (property "Tolerance" "1%")
    (property "Val" "100k")
    (attr smd)
    (fp_text reference "R58" (at 0.84 0.36 90) (layer "F.SilkS")
      (effects (font (size 0.7 0.7) (thickness 0.15)) (justify left bottom))
    )
    (fp_text value "R_100k_0402" (at 0 1.4 90) (layer "F.Fab")
      (effects (font (size 0.7 0.7) (thickness 0.15)) (justify left bottom))
    )
    (fp_text user "${REFERENCE}" (at -0.95 3.168 90) (layer "F.Fab") hide
      (effects (font (size 0.7 0.7) (thickness 0.15)) (justify left bottom))
    )
    (fp_text user "License: Apache-2.0" (at -0.95 5.169 90) (layer "F.Fab") hide
      (effects (font (size 0.7 0.7) (thickness 0.15)) (justify left bottom))
    )
    (fp_text user "Author: Antmicro" (at -0.95 4.169 90) (layer "F.Fab") hide
      (effects (font (size 0.7 0.7) (thickness 0.15)) (justify left bottom))
    )
    (fp_rect (start -0.93 -0.47) (end 0.93 0.47) (layer "F.CrtYd") (width 0.05) (fill none))
    (fp_rect (start -0.5 -0.25) (end 0.5 0.25) (layer "F.Fab") (width 0.15) (fill none))
    (pad "1" smd roundrect (at -0.485 0 90) (size 0.59 0.64) (layers "F.Cu" "F.Paste" "F.Mask") (roundrect_rratio 0.25)
      (net 328 "/USB-C Interface /USB_SBU_NP_N") (pintype "passive"))
    (pad "2" smd roundrect (at 0.485 0 90) (size 0.59 0.64) (layers "F.Cu" "F.Paste" "F.Mask") (roundrect_rratio 0.25)
      (net 1 "GND") (pintype "passive"))
  )
	(footprint "sa800u-baseboard-hw-footprints:R_0402_1005Metric" (layer "F.Cu")
    (tedit 5FD9C158)
    (at 96.1 139.8 90)
    (descr "Resistor SMD 0402")
    (tags "resistor SMD 0402")
    (property "Author" "Antmicro")
    (property "License" "Apache-2.0")
    (property "MPN" "CR0402-FX-1003GLF")
    (property "Manufacturer" "Bourns")
    (property "Sheetfile" "usb-c-interface.kicad_sch")
    (property "Sheetname" "USB-C Interface ")
    (property "Tolerance" "1%")
    (property "Val" "100k")
    (attr smd)
    (fp_text reference "R57" (at 0.87 0.43 90) (layer "F.SilkS")
      (effects (font (size 0.7 0.7) (thickness 0.15)) (justify left bottom))
    )
    (fp_text value "R_100k_0402" (at 0 1.4 90) (layer "F.Fab")
      (effects (font (size 0.7 0.7) (thickness 0.15)) (justify left bottom))
    )
    (fp_text user "License: Apache-2.0" (at -0.95 5.169 90) (layer "F.Fab") hide
      (effects (font (size 0.7 0.7) (thickness 0.15)) (justify left bottom))
    )
    (fp_text user "Author: Antmicro" (at -0.95 4.169 90) (layer "F.Fab") hide
      (effects (font (size 0.7 0.7) (thickness 0.15)) (justify left bottom))
    )
    (fp_text user "${REFERENCE}" (at -0.95 3.168 90) (layer "F.Fab") hide
      (effects (font (size 0.7 0.7) (thickness 0.15)) (justify left bottom))
    )
    (fp_rect (start -0.93 -0.47) (end 0.93 0.47) (layer "F.CrtYd") (width 0.05) (fill none))
    (fp_rect (start -0.5 -0.25) (end 0.5 0.25) (layer "F.Fab") (width 0.15) (fill none))
    (pad "1" smd roundrect (at -0.485 0 90) (size 0.59 0.64) (layers "F.Cu" "F.Paste" "F.Mask") (roundrect_rratio 0.25)
      (net 329 "/USB-C Interface /USB_SBU_NP_P") (pintype "passive"))
    (pad "2" smd roundrect (at 0.485 0 90) (size 0.59 0.64) (layers "F.Cu" "F.Paste" "F.Mask") (roundrect_rratio 0.25)
      (net 131 "3V3_SYS") (pintype "passive"))
  )
	(footprint "sa800u-baseboard-hw-footprints:C_0402_1005Metric" (layer "F.Cu")
    (tedit 616D63CF)
    (at 94.1 139.8 -90)
    (descr "Capacitor SMD 0402")
    (tags "capacitor SMD 0402")
    (property "Author" "Antmicro")
    (property "Dielectric" "X5R")
    (property "License" "Apache-2.0")
    (property "MPN" "GRM155R61H104KE14D")
    (property "Manufacturer" "Murata")
    (property "Sheetfile" "usb-c-interface.kicad_sch")
    (property "Sheetname" "USB-C Interface ")
    (property "Val" "100n")
    (property "Voltage" "50V")
    (attr smd)
    (fp_text reference "C61" (at -0.87 -0.38 -90) (layer "F.SilkS")
      (effects (font (size 0.7 0.7) (thickness 0.15)) (justify left bottom))
    )
    (fp_text value "C_100n_0402" (at 0 1.4 -90) (layer "F.Fab")
      (effects (font (size 0.7 0.7) (thickness 0.15)) (justify left bottom))
    )
    (fp_text user "Author: Antmicro" (at -0.932 4.17 -90) (layer "F.Fab") hide
      (effects (font (size 0.7 0.7) (thickness 0.15)) (justify left bottom))
    )
    (fp_text user "${REFERENCE}" (at -0.932 3.168 -90) (layer "F.Fab") hide
      (effects (font (size 0.7 0.7) (thickness 0.15)) (justify left bottom))
    )
    (fp_text user "License: Apache-2.0" (at -0.932 5.17 -90) (layer "F.Fab") hide
      (effects (font (size 0.7 0.7) (thickness 0.15)) (justify left bottom))
    )
    (fp_rect (start -0.94 -0.47) (end 0.94 0.47) (layer "F.CrtYd") (width 0.05) (fill none))
    (fp_rect (start -0.499 -0.249) (end 0.499 0.249) (layer "F.Fab") (width 0.15) (fill none))
    (pad "1" smd roundrect (at -0.484 0 270) (size 0.59 0.64) (layers "F.Cu" "F.Paste" "F.Mask") (roundrect_rratio 0.25)
      (net 10 "EDP_AUX_N") (pintype "passive"))
    (pad "2" smd roundrect (at 0.484 0 270) (size 0.59 0.64) (layers "F.Cu" "F.Paste" "F.Mask") (roundrect_rratio 0.25)
      (net 328 "/USB-C Interface /USB_SBU_NP_N") (pintype "passive"))
  )
	(footprint "sa800u-baseboard-hw-footprints:C_0402_1005Metric" (layer "F.Cu")
    (tedit 616D63CF)
    (at 94.7 145.8 -90)
    (descr "Capacitor SMD 0402")
    (tags "capacitor SMD 0402")
    (property "Author" "Antmicro")
    (property "Dielectric" "")
    (property "License" "Apache-2.0")
    (property "MPN" "C1005X6S1A105K050BC")
    (property "Manufacturer" "TDK")
    (property "Sheetfile" "usb-c-interface.kicad_sch")
    (property "Sheetname" "USB-C Interface ")
    (property "Val" "1u")
    (property "Voltage" "")
    (attr smd)
    (fp_text reference "C66" (at 1.1 -1.23 -90) (layer "F.SilkS")
      (effects (font (size 0.7 0.7) (thickness 0.15)) (justify left bottom))
    )
    (fp_text value "C_1u_0402" (at 0 1.4 -90) (layer "F.Fab")
      (effects (font (size 0.7 0.7) (thickness 0.15)) (justify left bottom))
    )
    (fp_text user "${REFERENCE}" (at -0.932 3.168 -90) (layer "F.Fab") hide
      (effects (font (size 0.7 0.7) (thickness 0.15)) (justify left bottom))
    )
    (fp_text user "Author: Antmicro" (at -0.932 4.17 -90) (layer "F.Fab") hide
      (effects (font (size 0.7 0.7) (thickness 0.15)) (justify left bottom))
    )
    (fp_text user "License: Apache-2.0" (at -0.932 5.17 -90) (layer "F.Fab") hide
      (effects (font (size 0.7 0.7) (thickness 0.15)) (justify left bottom))
    )
    (fp_rect (start -0.94 -0.47) (end 0.94 0.47) (layer "F.CrtYd") (width 0.05) (fill none))
    (fp_rect (start -0.499 -0.249) (end 0.499 0.249) (layer "F.Fab") (width 0.15) (fill none))
    (pad "1" smd roundrect (at -0.484 0 270) (size 0.59 0.64) (layers "F.Cu" "F.Paste" "F.Mask") (roundrect_rratio 0.25)
      (net 131 "3V3_SYS") (pintype "passive"))
    (pad "2" smd roundrect (at 0.484 0 270) (size 0.59 0.64) (layers "F.Cu" "F.Paste" "F.Mask") (roundrect_rratio 0.25)
      (net 1 "GND") (pintype "passive"))
  )
)
